(kicad_pcb
	(version 20241229)
	(generator "pcbnew")
	(generator_version "9.0")
	(general
		(thickness 1.62)
		(legacy_teardrops no)
	)
	(paper "A3")
	(title_block
		(title "COM Express 7 Baseboard")
		(date "2025-02-04")
		(rev "1.1.2")
		(company "Antmicro Ltd")
		(comment 1 "www.antmicro.com")
		(comment 9 "footprints 380-385 of 802")
	)
	(layers
		(0 "F.Cu" signal)
		(4 "In1.Cu" signal)
		(6 "In2.Cu" signal)
		(8 "In3.Cu" signal)
		(10 "In4.Cu" signal)
		(12 "In5.Cu" signal)
		(14 "In6.Cu" signal)
		(2 "B.Cu" signal)
		(9 "F.Adhes" user "F.Adhesive")
		(11 "B.Adhes" user "B.Adhesive")
		(13 "F.Paste" user)
		(15 "B.Paste" user)
		(5 "F.SilkS" user "F.Silkscreen")
		(7 "B.SilkS" user "B.Silkscreen")
		(1 "F.Mask" user)
		(3 "B.Mask" user)
		(17 "Dwgs.User" user "User.Drawings")
		(19 "Cmts.User" user "User.Comments")
		(21 "Eco1.User" user "User.Eco1")
		(23 "Eco2.User" user "User.Eco2")
		(25 "Edge.Cuts" user)
		(27 "Margin" user)
		(31 "F.CrtYd" user "F.Courtyard")
		(29 "B.CrtYd" user "B.Courtyard")
		(35 "F.Fab" user)
		(33 "B.Fab" user)
	)
	(footprint "antmicro-footprints:R_0402_1005Metric"
		(layer "F.Cu")
		(at 252.614999 81.174999)
		(descr "Resistor SMD 0402")
		(tags "resistor SMD 0402")
		(property "Reference" "R143"
			(at -0.825 0.435001 0)
			(layer "F.SilkS")
			(effects
				(font
					(size 0.7 0.7)
					(thickness 0.15)
				)
				(justify right bottom)
			)
		)
		(property "Value" "R_0R_0402"
			(at -1.011843 1.772047 0)
			(layer "F.Fab")
			(effects
				(font
					(size 0.7 0.7)
					(thickness 0.15)
				)
				(justify left bottom)
			)
		)
		(property "Datasheet" "https://industrial.panasonic.com/cdbs/www-data/pdf/RDA0000/AOA0000C301.pdf"
			(at 0 0 0)
			(layer "F.Fab")
			(hide yes)
			(effects
				(font
					(size 1.27 1.27)
					(thickness 0.15)
				)
			)
		)
		(property "Author" "Antmicro"
			(at 0 0 0)
			(layer "F.Fab")
			(hide yes)
			(effects
				(font
					(size 1 1)
					(thickness 0.15)
				)
			)
		)
		(property "Current" "1A"
			(at 0 0 0)
			(layer "F.Fab")
			(hide yes)
			(effects
				(font
					(size 1 1)
					(thickness 0.15)
				)
			)
		)
		(property "License" "Apache-2.0"
			(at 0 0 0)
			(layer "F.Fab")
			(hide yes)
			(effects
				(font
					(size 1 1)
					(thickness 0.15)
				)
			)
		)
		(property "MPN" "ERJ2GE0R00X"
			(at 0 0 0)
			(layer "F.Fab")
			(hide yes)
			(effects
				(font
					(size 1 1)
					(thickness 0.15)
				)
			)
		)
		(property "Manufacturer" "Panasonic"
			(at 0 0 0)
			(layer "F.Fab")
			(hide yes)
			(effects
				(font
					(size 1 1)
					(thickness 0.15)
				)
			)
		)
		(property "Public" "False"
			(at 0 0 0)
			(layer "F.Fab")
			(hide yes)
			(effects
				(font
					(size 1 1)
					(thickness 0.15)
				)
			)
		)
		(property "Tolerance" ""
			(at 0 0 0)
			(layer "F.Fab")
			(hide yes)
			(effects
				(font
					(size 1 1)
					(thickness 0.15)
				)
			)
		)
		(property "Val" "0R"
			(at 0 0 0)
			(layer "F.Fab")
			(hide yes)
			(effects
				(font
					(size 1 1)
					(thickness 0.15)
				)
			)
		)
		(sheetname "Misc")
		(sheetfile "misc.kicad_sch")
		(attr smd)
		(fp_rect
			(start -0.925 -0.47)
			(end 0.925 0.47)
			(stroke
				(width 0.05)
				(type default)
			)
			(fill no)
			(layer "F.CrtYd")
		)
		(fp_rect
			(start -0.5 -0.25)
			(end 0.5 0.25)
			(stroke
				(width 0.15)
				(type solid)
			)
			(fill no)
			(layer "F.Fab")
		)
		(pad "1" smd roundrect
			(at -0.48 0)
			(size 0.59 0.64)
			(layers "F.Cu" "F.Mask" "F.Paste")
			(roundrect_rratio 0.25)
			(net 1 "GND")
			(pintype "passive")
			(teardrops
				(best_length_ratio 0.2)
				(max_length 1)
				(best_width_ratio 0.9)
				(max_width 2)
				(curved_edges yes)
				(filter_ratio 0.9)
				(enabled yes)
				(allow_two_segments yes)
				(prefer_zone_connections yes)
			)
		)
		(pad "2" smd roundrect
			(at 0.48 0)
			(size 0.59 0.64)
			(layers "F.Cu" "F.Mask" "F.Paste")
			(roundrect_rratio 0.25)
			(net 588 "/Misc/~{ADDREN}")
			(pintype "passive")
			(teardrops
				(best_length_ratio 0.2)
				(max_length 1)
				(best_width_ratio 0.9)
				(max_width 2)
				(curved_edges yes)
				(filter_ratio 0.9)
				(enabled yes)
				(allow_two_segments yes)
				(prefer_zone_connections yes)
			)
		)
	)
	(footprint "antmicro-footprints:TP_SMD_0.75mm"
		(layer "F.Cu")
		(at 195.70861 72.802163 -90)
		(property "Reference" "TP104"
			(at 0 -0.6 90)
			(layer "F.SilkS")
			(hide yes)
			(effects
				(font
					(size 0.7 0.7)
					(thickness 0.15)
				)
				(justify right bottom)
			)
		)
		(property "Value" "TP_0.75mm_SMD"
			(at 0 1.2 90)
			(layer "F.Fab")
			(effects
				(font
					(size 0.7 0.7)
					(thickness 0.15)
				)
				(justify right bottom)
			)
		)
		(property "Author" "Antmicro"
			(at 122.906447 268.510773 0)
			(layer "F.Fab")
			(hide yes)
			(effects
				(font
					(size 1 1)
					(thickness 0.15)
				)
			)
		)
		(property "License" "Apache-2.0"
			(at 122.906447 268.510773 0)
			(layer "F.Fab")
			(hide yes)
			(effects
				(font
					(size 1 1)
					(thickness 0.15)
				)
			)
		)
		(property "MPN" ""
			(at 122.906447 268.510773 0)
			(layer "F.Fab")
			(hide yes)
			(effects
				(font
					(size 1 1)
					(thickness 0.15)
				)
			)
		)
		(property "Manufacturer" ""
			(at 122.906447 268.510773 0)
			(layer "F.Fab")
			(hide yes)
			(effects
				(font
					(size 1 1)
					(thickness 0.15)
				)
			)
		)
		(property "Public" "False"
			(at 122.906447 268.510773 0)
			(layer "F.Fab")
			(hide yes)
			(effects
				(font
					(size 1 1)
					(thickness 0.15)
				)
			)
		)
		(sheetname "Power")
		(sheetfile "power.kicad_sch")
		(attr exclude_from_pos_files exclude_from_bom)
		(fp_circle
			(center 0 0)
			(end 0.475 0)
			(stroke
				(width 0.05)
				(type default)
			)
			(fill no)
			(layer "F.CrtYd")
		)
		(pad "1" smd circle
			(at 0 0 270)
			(size 0.75 0.75)
			(layers "F.Cu" "F.Mask")
			(net 52 "+5V")
			(pinfunction "1")
			(pintype "passive")
			(teardrops
				(best_length_ratio 0.4)
				(max_length 1)
				(best_width_ratio 0.9)
				(max_width 2)
				(curved_edges yes)
				(filter_ratio 0.9)
				(enabled yes)
				(allow_two_segments yes)
				(prefer_zone_connections yes)
			)
		)
	)
	(footprint "antmicro-footprints:C_0402_1005Metric"
		(layer "F.Cu")
		(at 244.05 126.71)
		(descr "Capacitor SMD 0402")
		(tags "capacitor SMD 0402")
		(property "Reference" "C102"
			(at -1.4 -0.45 0)
			(layer "F.SilkS")
			(effects
				(font
					(size 0.7 0.7)
					(thickness 0.15)
				)
				(justify left bottom)
			)
		)
		(property "Value" "C_100n_0402"
			(at -1.022927 2.155213 0)
			(layer "F.Fab")
			(effects
				(font
					(size 0.7 0.7)
					(thickness 0.15)
				)
				(justify left bottom)
			)
		)
		(property "Datasheet" "https://www.murata.com/products/productdetail?partno=GRM155R61H104KE14%23"
			(at 0 0 0)
			(layer "F.Fab")
			(hide yes)
			(effects
				(font
					(size 1.27 1.27)
					(thickness 0.15)
				)
			)
		)
		(property "Author" "Antmicro"
			(at 0 0 0)
			(layer "F.Fab")
			(hide yes)
			(effects
				(font
					(size 1 1)
					(thickness 0.15)
				)
			)
		)
		(property "Dielectric" "X5R"
			(at 0 0 0)
			(layer "F.Fab")
			(hide yes)
			(effects
				(font
					(size 1 1)
					(thickness 0.15)
				)
			)
		)
		(property "License" "Apache-2.0"
			(at 0 0 0)
			(layer "F.Fab")
			(hide yes)
			(effects
				(font
					(size 1 1)
					(thickness 0.15)
				)
			)
		)
		(property "MPN" "GRM155R61H104KE14D"
			(at 0 0 0)
			(layer "F.Fab")
			(hide yes)
			(effects
				(font
					(size 1 1)
					(thickness 0.15)
				)
			)
		)
		(property "Manufacturer" "Murata"
			(at 0 0 0)
			(layer "F.Fab")
			(hide yes)
			(effects
				(font
					(size 1 1)
					(thickness 0.15)
				)
			)
		)
		(property "Public" "False"
			(at 0 0 0)
			(layer "F.Fab")
			(hide yes)
			(effects
				(font
					(size 1 1)
					(thickness 0.15)
				)
			)
		)
		(property "Val" "100n"
			(at 0 0 0)
			(layer "F.Fab")
			(hide yes)
			(effects
				(font
					(size 1 1)
					(thickness 0.15)
				)
			)
		)
		(property "Voltage" "50V"
			(at 0 0 0)
			(layer "F.Fab")
			(hide yes)
			(effects
				(font
					(size 1 1)
					(thickness 0.15)
				)
			)
		)
		(sheetname "Com Express 7 MGMT")
		(sheetfile "com_express_7_mgmt.kicad_sch")
		(attr smd)
		(fp_rect
			(start -0.925 -0.47)
			(end 0.925 0.47)
			(stroke
				(width 0.05)
				(type default)
			)
			(fill no)
			(layer "F.CrtYd")
		)
		(fp_line
			(start -0.494 -0.25)
			(end 0.504 -0.25)
			(stroke
				(width 0.15)
				(type solid)
			)
			(layer "F.Fab")
		)
		(fp_line
			(start -0.494 0.248)
			(end -0.494 -0.25)
			(stroke
				(width 0.15)
				(type solid)
			)
			(layer "F.Fab")
		)
		(fp_line
			(start 0.504 -0.25)
			(end 0.504 0.248)
			(stroke
				(width 0.15)
				(type solid)
			)
			(layer "F.Fab")
		)
		(fp_line
			(start 0.504 0.248)
			(end -0.494 0.248)
			(stroke
				(width 0.15)
				(type solid)
			)
			(layer "F.Fab")
		)
		(pad "1" smd roundrect
			(at -0.48 0)
			(size 0.59 0.64)
			(layers "F.Cu" "F.Mask" "F.Paste")
			(roundrect_rratio 0.25)
			(net 1 "GND")
			(pintype "passive")
			(teardrops
				(best_length_ratio 0.2)
				(max_length 1)
				(best_width_ratio 0.9)
				(max_width 2)
				(curved_edges yes)
				(filter_ratio 0.9)
				(enabled yes)
				(allow_two_segments yes)
				(prefer_zone_connections yes)
			)
		)
		(pad "2" smd roundrect
			(at 0.48 0)
			(size 0.59 0.64)
			(layers "F.Cu" "F.Mask" "F.Paste")
			(roundrect_rratio 0.25)
			(net 73 "+3V3_AON")
			(pintype "passive")
			(teardrops
				(best_length_ratio 0.2)
				(max_length 1)
				(best_width_ratio 0.9)
				(max_width 2)
				(curved_edges yes)
				(filter_ratio 0.9)
				(enabled yes)
				(allow_two_segments yes)
				(prefer_zone_connections yes)
			)
		)
	)
	(footprint "antmicro-footprints:R_0402_1005Metric"
		(layer "F.Cu")
		(at 126.425 85.060001 180)
		(descr "Resistor SMD 0402")
		(tags "resistor SMD 0402")
		(property "Reference" "R240"
			(at -1.575 -6.4 0)
			(layer "F.SilkS")
			(effects
				(font
					(size 0.7 0.7)
					(thickness 0.15)
				)
				(justify right bottom)
			)
		)
		(property "Value" "R_0R_0402"
			(at -1.011843 1.772047 0)
			(layer "F.Fab")
			(effects
				(font
					(size 0.7 0.7)
					(thickness 0.15)
				)
				(justify right bottom)
			)
		)
		(property "Datasheet" "https://industrial.panasonic.com/cdbs/www-data/pdf/RDA0000/AOA0000C301.pdf"
			(at 0 0 180)
			(layer "F.Fab")
			(hide yes)
			(effects
				(font
					(size 1.27 1.27)
					(thickness 0.15)
				)
			)
		)
		(property "Author" "Antmicro"
			(at 252.85 170.120002 0)
			(layer "F.Fab")
			(hide yes)
			(effects
				(font
					(size 1 1)
					(thickness 0.15)
				)
			)
		)
		(property "Current" "1A"
			(at 252.85 170.120002 0)
			(layer "F.Fab")
			(hide yes)
			(effects
				(font
					(size 1 1)
					(thickness 0.15)
				)
			)
		)
		(property "License" "Apache-2.0"
			(at 252.85 170.120002 0)
			(layer "F.Fab")
			(hide yes)
			(effects
				(font
					(size 1 1)
					(thickness 0.15)
				)
			)
		)
		(property "MPN" "ERJ2GE0R00X"
			(at 252.85 170.120002 0)
			(layer "F.Fab")
			(hide yes)
			(effects
				(font
					(size 1 1)
					(thickness 0.15)
				)
			)
		)
		(property "Manufacturer" "Panasonic"
			(at 252.85 170.120002 0)
			(layer "F.Fab")
			(hide yes)
			(effects
				(font
					(size 1 1)
					(thickness 0.15)
				)
			)
		)
		(property "Public" "False"
			(at 252.85 170.120002 0)
			(layer "F.Fab")
			(hide yes)
			(effects
				(font
					(size 1 1)
					(thickness 0.15)
				)
			)
		)
		(property "Tolerance" ""
			(at 252.85 170.120002 0)
			(layer "F.Fab")
			(hide yes)
			(effects
				(font
					(size 1 1)
					(thickness 0.15)
				)
			)
		)
		(property "Val" "0R"
			(at 252.85 170.120002 0)
			(layer "F.Fab")
			(hide yes)
			(effects
				(font
					(size 1 1)
					(thickness 0.15)
				)
			)
		)
		(sheetname "GPIO expander")
		(sheetfile "gpio_exp.kicad_sch")
		(attr smd)
		(fp_rect
			(start -0.925 -0.47)
			(end 0.925 0.47)
			(stroke
				(width 0.05)
				(type default)
			)
			(fill no)
			(layer "F.CrtYd")
		)
		(fp_rect
			(start -0.5 -0.25)
			(end 0.5 0.25)
			(stroke
				(width 0.15)
				(type solid)
			)
			(fill no)
			(layer "F.Fab")
		)
		(pad "1" smd roundrect
			(at -0.48 0 180)
			(size 0.59 0.64)
			(layers "F.Cu" "F.Mask" "F.Paste")
			(roundrect_rratio 0.25)
			(net 641 "Net-(U41-IO0_2)")
			(pintype "passive")
			(teardrops
				(best_length_ratio 0.2)
				(max_length 1)
				(best_width_ratio 0.9)
				(max_width 2)
				(curved_edges yes)
				(filter_ratio 0.9)
				(enabled yes)
				(allow_two_segments yes)
				(prefer_zone_connections yes)
			)
		)
		(pad "2" smd roundrect
			(at 0.48 0 180)
			(size 0.59 0.64)
			(layers "F.Cu" "F.Mask" "F.Paste")
			(roundrect_rratio 0.25)
			(net 944 "/GPIO expander/GPIOEX2")
			(pintype "passive")
			(teardrops
				(best_length_ratio 0.2)
				(max_length 1)
				(best_width_ratio 0.9)
				(max_width 2)
				(curved_edges yes)
				(filter_ratio 0.9)
				(enabled yes)
				(allow_two_segments yes)
				(prefer_zone_connections yes)
			)
		)
	)
	(footprint "antmicro-footprints:R_0402_1005Metric"
		(layer "F.Cu")
		(at 115.4 144.36 90)
		(descr "Resistor SMD 0402")
		(tags "resistor SMD 0402")
		(property "Reference" "R206"
			(at 0.8 0.4 90)
			(layer "F.SilkS")
			(effects
				(font
					(size 0.7 0.7)
					(thickness 0.15)
				)
				(justify left bottom)
			)
		)
		(property "Value" "R_1k_0402"
			(at -1.011843 1.772047 90)
			(layer "F.Fab")
			(effects
				(font
					(size 0.7 0.7)
					(thickness 0.15)
				)
				(justify left bottom)
			)
		)
		(property "Datasheet" "https://www.bourns.com/docs/product-datasheets/cr.pdf"
			(at 0 0 90)
			(layer "F.Fab")
			(hide yes)
			(effects
				(font
					(size 1.27 1.27)
					(thickness 0.15)
				)
			)
		)
		(property "Author" "Antmicro"
			(at 259.76 28.96 0)
			(layer "F.Fab")
			(hide yes)
			(effects
				(font
					(size 1 1)
					(thickness 0.15)
				)
			)
		)
		(property "License" "Apache-2.0"
			(at 259.76 28.96 0)
			(layer "F.Fab")
			(hide yes)
			(effects
				(font
					(size 1 1)
					(thickness 0.15)
				)
			)
		)
		(property "MPN" "CR0402-FX-1001GLF"
			(at 259.76 28.96 0)
			(layer "F.Fab")
			(hide yes)
			(effects
				(font
					(size 1 1)
					(thickness 0.15)
				)
			)
		)
		(property "Manufacturer" "Bourns"
			(at 259.76 28.96 0)
			(layer "F.Fab")
			(hide yes)
			(effects
				(font
					(size 1 1)
					(thickness 0.15)
				)
			)
		)
		(property "Public" "False"
			(at 259.76 28.96 0)
			(layer "F.Fab")
			(hide yes)
			(effects
				(font
					(size 1 1)
					(thickness 0.15)
				)
			)
		)
		(property "Tolerance" "1%"
			(at 259.76 28.96 0)
			(layer "F.Fab")
			(hide yes)
			(effects
				(font
					(size 1 1)
					(thickness 0.15)
				)
			)
		)
		(property "Val" "1k"
			(at 259.76 28.96 0)
			(layer "F.Fab")
			(hide yes)
			(effects
				(font
					(size 1 1)
					(thickness 0.15)
				)
			)
		)
		(sheetname "PCIe redriver")
		(sheetfile "pcie_redriver.kicad_sch")
		(attr smd)
		(fp_rect
			(start -0.925 -0.47)
			(end 0.925 0.47)
			(stroke
				(width 0.05)
				(type default)
			)
			(fill no)
			(layer "F.CrtYd")
		)
		(fp_rect
			(start -0.5 -0.25)
			(end 0.5 0.25)
			(stroke
				(width 0.15)
				(type solid)
			)
			(fill no)
			(layer "F.Fab")
		)
		(pad "1" smd roundrect
			(at -0.48 0 90)
			(size 0.59 0.64)
			(layers "F.Cu" "F.Mask" "F.Paste")
			(roundrect_rratio 0.25)
			(net 2 "+3V3")
			(pintype "passive")
			(teardrops
				(best_length_ratio 0.2)
				(max_length 1)
				(best_width_ratio 0.9)
				(max_width 2)
				(curved_edges yes)
				(filter_ratio 0.9)
				(enabled yes)
				(allow_two_segments yes)
				(prefer_zone_connections yes)
			)
		)
		(pad "2" smd roundrect
			(at 0.48 0 90)
			(size 0.59 0.64)
			(layers "F.Cu" "F.Mask" "F.Paste")
			(roundrect_rratio 0.25)
			(net 625 "/PCIe redriver/TX_EQ2")
			(pintype "passive")
			(teardrops
				(best_length_ratio 0.2)
				(max_length 1)
				(best_width_ratio 0.9)
				(max_width 2)
				(curved_edges yes)
				(filter_ratio 0.9)
				(enabled yes)
				(allow_two_segments yes)
				(prefer_zone_connections yes)
			)
		)
	)
	(footprint "antmicro-footprints:R_0402_1005Metric"
		(layer "F.Cu")
		(at 124.21 144.05)
		(descr "Resistor SMD 0402")
		(tags "resistor SMD 0402")
		(property "Reference" "R281"
			(at -3.61 0.46 0)
			(layer "F.SilkS")
			(effects
				(font
					(size 0.7 0.7)
					(thickness 0.15)
				)
				(justify left bottom)
			)
		)
		(property "Value" "R_0R_0402"
			(at -1.011843 1.772047 0)
			(layer "F.Fab")
			(effects
				(font
					(size 0.7 0.7)
					(thickness 0.15)
				)
				(justify left bottom)
			)
		)
		(property "Datasheet" "https://industrial.panasonic.com/cdbs/www-data/pdf/RDA0000/AOA0000C301.pdf"
			(at 0 0 0)
			(layer "F.Fab")
			(hide yes)
			(effects
				(font
					(size 1.27 1.27)
					(thickness 0.15)
				)
			)
		)
		(property "Author" "Antmicro"
			(at 0 0 0)
			(layer "F.Fab")
			(hide yes)
			(effects
				(font
					(size 1 1)
					(thickness 0.15)
				)
			)
		)
		(property "Current" "1A"
			(at 0 0 0)
			(layer "F.Fab")
			(hide yes)
			(effects
				(font
					(size 1 1)
					(thickness 0.15)
				)
			)
		)
		(property "License" "Apache-2.0"
			(at 0 0 0)
			(layer "F.Fab")
			(hide yes)
			(effects
				(font
					(size 1 1)
					(thickness 0.15)
				)
			)
		)
		(property "MPN" "ERJ2GE0R00X"
			(at 0 0 0)
			(layer "F.Fab")
			(hide yes)
			(effects
				(font
					(size 1 1)
					(thickness 0.15)
				)
			)
		)
		(property "Manufacturer" "Panasonic"
			(at 0 0 0)
			(layer "F.Fab")
			(hide yes)
			(effects
				(font
					(size 1 1)
					(thickness 0.15)
				)
			)
		)
		(property "Public" "False"
			(at 0 0 0)
			(layer "F.Fab")
			(hide yes)
			(effects
				(font
					(size 1 1)
					(thickness 0.15)
				)
			)
		)
		(property "Tolerance" ""
			(at 0 0 0)
			(layer "F.Fab")
			(hide yes)
			(effects
				(font
					(size 1 1)
					(thickness 0.15)
				)
			)
		)
		(property "Val" "0R"
			(at 0 0 0)
			(layer "F.Fab")
			(hide yes)
			(effects
				(font
					(size 1 1)
					(thickness 0.15)
				)
			)
		)
		(sheetname "KR to SFI #2")
		(sheetfile "kr_sfi.kicad_sch")
		(attr smd)
		(fp_rect
			(start -0.925 -0.47)
			(end 0.925 0.47)
			(stroke
				(width 0.05)
				(type default)
			)
			(fill no)
			(layer "F.CrtYd")
		)
		(fp_rect
			(start -0.5 -0.25)
			(end 0.5 0.25)
			(stroke
				(width 0.15)
				(type solid)
			)
			(fill no)
			(layer "F.Fab")
		)
		(pad "1" smd roundrect
			(at -0.48 0)
			(size 0.59 0.64)
			(layers "F.Cu" "F.Mask" "F.Paste")
			(roundrect_rratio 0.25)
			(net 669 "/2xSFP+/KR to SFI #2/MDIO_R")
			(pintype "passive")
			(teardrops
				(best_length_ratio 0.2)
				(max_length 1)
				(best_width_ratio 0.9)
				(max_width 2)
				(curved_edges yes)
				(filter_ratio 0.9)
				(enabled yes)
				(allow_two_segments yes)
				(prefer_zone_connections yes)
			)
		)
		(pad "2" smd roundrect
			(at 0.48 0)
			(size 0.59 0.64)
			(layers "F.Cu" "F.Mask" "F.Paste")
			(roundrect_rratio 0.25)
			(net 670 "/2xSFP+/KR to SFI #2/MDIO")
			(pintype "passive")
			(teardrops
				(best_length_ratio 0.2)
				(max_length 1)
				(best_width_ratio 0.9)
				(max_width 2)
				(curved_edges yes)
				(filter_ratio 0.9)
				(enabled yes)
				(allow_two_segments yes)
				(prefer_zone_connections yes)
			)
		)
	)
)
